(kicad_pcb
	(version 20260206)
	(generator "pcbnew")
	(generator_version "10.0")
	(general
		(thickness 1.6)
		(legacy_teardrops no)
	)
	(paper "A4")
	(title_block
		(title "Bryce Canyon_IOM_M2_16342-2_OCP.brd")
		(comment 1 "Bryce Canyon / footprints 925-932 of 1146")
	)
	(layers
		(0 "F.Cu" signal "TOP")
		(4 "In1.Cu" signal "L2GND")
		(6 "In2.Cu" signal "L3")
		(8 "In3.Cu" signal "L4VCC")
		(10 "In4.Cu" signal "L5VCC")
		(12 "In5.Cu" signal "L6")
		(14 "In6.Cu" signal "L7GND")
		(2 "B.Cu" signal "BOTTOM")
		(9 "F.Adhes" user "F.Adhesive")
		(11 "B.Adhes" user "B.Adhesive")
		(13 "F.Paste" user "Package Geometry/Pastemask Top")
		(15 "B.Paste" user "Package Geometry/Pastemask Bottom")
		(5 "F.SilkS" user "Ref Des/Silkscreen Top")
		(7 "B.SilkS" user "Ref Des/Silkscreen Bottom")
		(1 "F.Mask" user "Board Geometry/Soldermask Top")
		(3 "B.Mask" user "Board Geometry/Soldermask Bottom")
		(17 "Dwgs.User" user "User.Drawings")
		(19 "Cmts.User" user "User.Comments")
		(21 "Eco1.User" user "User.Eco1")
		(23 "Eco2.User" user "User.Eco2")
		(25 "Edge.Cuts" user "Board Geometry/Outline")
		(27 "Margin" user)
		(31 "F.CrtYd" user "Package Geometry/Place Bound Top")
		(29 "B.CrtYd" user "Package Geometry/Place Bound Bottom")
		(35 "F.Fab" user "Ref Des/Assembly Top")
		(33 "B.Fab" user "Ref Des/Assembly Bottom")
	)
	(footprint ""
		(layer "B.Cu")
		(at 23.437342 -129.1082 180)
		(property "Reference" "R248"
			(at 0 0 0)
			(layer "B.SilkS")
			(hide yes)
			(effects
				(font
					(size 1.27 1.27)
				)
				(justify mirror)
			)
		)
		(property "Value" "120R2F-GP"
			(at -0.064008 -3.993896 180)
			(unlocked yes)
			(layer "B.Fab")
			(hide yes)
			(effects
				(font
					(size 1.016 1.016)
					(thickness 0.1524)
				)
				(justify mirror)
			)
		)
		(property "Device Type" "R402H16"
			(at -0.064008 -5.517896 180)
			(unlocked yes)
			(layer "B.Fab")
			(hide yes)
			(effects
				(font
					(size 1.016 1.016)
					(thickness 0.1524)
				)
				(justify mirror)
			)
		)
		(duplicate_pad_numbers_are_jumpers no)
		(fp_line
			(start 0.508 -0.9398)
			(end 0.508 0.9398)
			(stroke
				(width 0.1524)
				(type default)
			)
			(layer "B.SilkS")
		)
		(fp_line
			(start -0.508 -0.9398)
			(end 0.508 -0.9398)
			(stroke
				(width 0.1524)
				(type default)
			)
			(layer "B.SilkS")
		)
		(fp_rect
			(start 0.508 0.9398)
			(end -0.508 -0.9398)
			(stroke
				(width 0)
				(type default)
			)
			(fill no)
			(layer "B.CrtYd")
		)
		(fp_rect
			(start 0.508 0.9398)
			(end -0.508 -0.9398)
			(stroke
				(width 0)
				(type default)
			)
			(fill no)
			(layer "B.Fab")
		)
		(pad "1" smd custom
			(at 0 -0.4445)
			(size 0.1397 0.1397)
			(layers "B.Cu" "B.Mask" "B.Paste")
			(net "GND")
			(options
				(clearance outline)
				(anchor circle)
			)
			(primitives
				(gr_poly
					(pts
						(arc
							(start -0.1778 0.2794)
							(mid -0.249642 0.249642)
							(end -0.2794 0.1778)
						)
						(arc
							(start -0.2794 -0.1778)
							(mid -0.249642 -0.249642)
							(end -0.1778 -0.2794)
						)
						(arc
							(start 0.1778 -0.2794)
							(mid 0.249642 -0.249642)
							(end 0.2794 -0.1778)
						)
						(arc
							(start 0.2794 0.1778)
							(mid 0.249642 0.249642)
							(end 0.1778 0.2794)
						)
					)
					(width 0)
					(fill yes)
				)
			)
		)
		(pad "2" smd custom
			(at 0 0.4445)
			(size 0.1397 0.1397)
			(layers "B.Cu" "B.Mask" "B.Paste")
			(net "MEMA_7")
			(options
				(clearance outline)
				(anchor circle)
			)
			(primitives
				(gr_poly
					(pts
						(arc
							(start -0.1778 0.2794)
							(mid -0.249642 0.249642)
							(end -0.2794 0.1778)
						)
						(arc
							(start -0.2794 -0.1778)
							(mid -0.249642 -0.249642)
							(end -0.1778 -0.2794)
						)
						(arc
							(start 0.1778 -0.2794)
							(mid 0.249642 -0.249642)
							(end 0.2794 -0.1778)
						)
						(arc
							(start 0.2794 0.1778)
							(mid 0.249642 0.249642)
							(end 0.1778 0.2794)
						)
					)
					(width 0)
					(fill yes)
				)
			)
		)
	)
	(footprint ""
		(layer "B.Cu")
		(at 40.679878 -136.439656)
		(property "Reference" "TP18"
			(at 0 0 0)
			(layer "B.SilkS")
			(hide yes)
			(effects
				(font
					(size 1.27 1.27)
				)
				(justify mirror)
			)
		)
		(property "Value" "TPAD28-2-GP"
			(at 0.0127 -1.6637 0)
			(unlocked yes)
			(layer "B.Fab")
			(hide yes)
			(effects
				(font
					(size 1.016 1.016)
					(thickness 0.1524)
				)
				(justify mirror)
			)
		)
		(property "Device Type" "TPAD28"
			(at 0.0127 -3.1877 0)
			(unlocked yes)
			(layer "B.Fab")
			(hide yes)
			(effects
				(font
					(size 1.016 1.016)
					(thickness 0.1524)
				)
				(justify mirror)
			)
		)
		(duplicate_pad_numbers_are_jumpers no)
		(fp_poly
			(pts
				(arc
					(start 0.3556 0)
					(mid -0.3556 0)
					(end 0.3556 0)
				)
			)
			(stroke
				(width 0)
				(type default)
			)
			(fill no)
			(layer "B.CrtYd")
		)
		(fp_poly
			(pts
				(arc
					(start 0.6096 0)
					(mid -0.6096 0)
					(end 0.6096 0)
				)
			)
			(stroke
				(width 0)
				(type default)
			)
			(fill no)
			(layer "B.Fab")
		)
		(pad "1" smd circle
			(at 0 0 180)
			(size 0.7112 0.7112)
			(layers "B.Cu" "B.Mask" "B.Paste")
			(net "TP_BMC_GPIOR4")
		)
	)
	(footprint ""
		(layer "B.Cu")
		(at 57.404 -148.8186 -90)
		(property "Reference" "R359"
			(at 0 0 90)
			(layer "B.SilkS")
			(hide yes)
			(effects
				(font
					(size 1.27 1.27)
				)
				(justify mirror)
			)
		)
		(property "Value" "10KR2F-2-GP"
			(at -0.064008 -3.993896 270)
			(unlocked yes)
			(layer "B.Fab")
			(hide yes)
			(effects
				(font
					(size 1.016 1.016)
					(thickness 0.1524)
				)
				(justify mirror)
			)
		)
		(property "Device Type" "R402H16"
			(at -0.064008 -5.517896 270)
			(unlocked yes)
			(layer "B.Fab")
			(hide yes)
			(effects
				(font
					(size 1.016 1.016)
					(thickness 0.1524)
				)
				(justify mirror)
			)
		)
		(duplicate_pad_numbers_are_jumpers no)
		(fp_line
			(start -0.508 -0.9398)
			(end 0.508 -0.9398)
			(stroke
				(width 0.1524)
				(type default)
			)
			(layer "B.SilkS")
		)
		(fp_line
			(start 0.508 -0.9398)
			(end 0.508 0.9398)
			(stroke
				(width 0.1524)
				(type default)
			)
			(layer "B.SilkS")
		)
		(fp_rect
			(start 0.508 0.9398)
			(end -0.508 -0.9398)
			(stroke
				(width 0)
				(type default)
			)
			(fill no)
			(layer "B.CrtYd")
		)
		(fp_rect
			(start 0.508 0.9398)
			(end -0.508 -0.9398)
			(stroke
				(width 0)
				(type default)
			)
			(fill no)
			(layer "B.Fab")
		)
		(pad "1" smd custom
			(at 0 -0.4445 90)
			(size 0.1397 0.1397)
			(layers "B.Cu" "B.Mask" "B.Paste")
			(net "P3V3_STBY")
			(options
				(clearance outline)
				(anchor circle)
			)
			(primitives
				(gr_poly
					(pts
						(arc
							(start -0.1778 0.2794)
							(mid -0.249642 0.249642)
							(end -0.2794 0.1778)
						)
						(arc
							(start -0.2794 -0.1778)
							(mid -0.249642 -0.249642)
							(end -0.1778 -0.2794)
						)
						(arc
							(start 0.1778 -0.2794)
							(mid 0.249642 -0.249642)
							(end 0.2794 -0.1778)
						)
						(arc
							(start 0.2794 0.1778)
							(mid 0.249642 0.249642)
							(end 0.1778 0.2794)
						)
					)
					(width 0)
					(fill yes)
				)
			)
		)
		(pad "2" smd custom
			(at 0 0.4445 90)
			(size 0.1397 0.1397)
			(layers "B.Cu" "B.Mask" "B.Paste")
			(net "JTAG_BMC_TMS")
			(options
				(clearance outline)
				(anchor circle)
			)
			(primitives
				(gr_poly
					(pts
						(arc
							(start -0.1778 0.2794)
							(mid -0.249642 0.249642)
							(end -0.2794 0.1778)
						)
						(arc
							(start -0.2794 -0.1778)
							(mid -0.249642 -0.249642)
							(end -0.1778 -0.2794)
						)
						(arc
							(start 0.1778 -0.2794)
							(mid 0.249642 -0.249642)
							(end 0.2794 -0.1778)
						)
						(arc
							(start 0.2794 0.1778)
							(mid 0.249642 0.249642)
							(end 0.1778 0.2794)
						)
					)
					(width 0)
					(fill yes)
				)
			)
		)
	)
	(footprint ""
		(layer "B.Cu")
		(at 73.224644 -146.81708 180)
		(property "Reference" "R53"
			(at 0 0 0)
			(layer "B.SilkS")
			(hide yes)
			(effects
				(font
					(size 1.27 1.27)
				)
				(justify mirror)
			)
		)
		(property "Value" "4K7R2F-GP"
			(at -0.064008 -3.993896 180)
			(unlocked yes)
			(layer "B.Fab")
			(hide yes)
			(effects
				(font
					(size 1.016 1.016)
					(thickness 0.1524)
				)
				(justify mirror)
			)
		)
		(property "Device Type" "R402H16"
			(at -0.064008 -5.517896 180)
			(unlocked yes)
			(layer "B.Fab")
			(hide yes)
			(effects
				(font
					(size 1.016 1.016)
					(thickness 0.1524)
				)
				(justify mirror)
			)
		)
		(duplicate_pad_numbers_are_jumpers no)
		(fp_line
			(start 0.508 -0.9398)
			(end 0.508 0.9398)
			(stroke
				(width 0.1524)
				(type default)
			)
			(layer "B.SilkS")
		)
		(fp_line
			(start -0.508 -0.9398)
			(end 0.508 -0.9398)
			(stroke
				(width 0.1524)
				(type default)
			)
			(layer "B.SilkS")
		)
		(fp_rect
			(start 0.508 0.9398)
			(end -0.508 -0.9398)
			(stroke
				(width 0)
				(type default)
			)
			(fill no)
			(layer "B.CrtYd")
		)
		(fp_rect
			(start 0.508 0.9398)
			(end -0.508 -0.9398)
			(stroke
				(width 0)
				(type default)
			)
			(fill no)
			(layer "B.Fab")
		)
		(pad "1" smd custom
			(at 0 -0.4445)
			(size 0.1397 0.1397)
			(layers "B.Cu" "B.Mask" "B.Paste")
			(net "P3V3_STBY")
			(options
				(clearance outline)
				(anchor circle)
			)
			(primitives
				(gr_poly
					(pts
						(arc
							(start -0.1778 0.2794)
							(mid -0.249642 0.249642)
							(end -0.2794 0.1778)
						)
						(arc
							(start -0.2794 -0.1778)
							(mid -0.249642 -0.249642)
							(end -0.1778 -0.2794)
						)
						(arc
							(start 0.1778 -0.2794)
							(mid 0.249642 -0.249642)
							(end 0.2794 -0.1778)
						)
						(arc
							(start 0.2794 0.1778)
							(mid 0.249642 0.249642)
							(end 0.1778 0.2794)
						)
					)
					(width 0)
					(fill yes)
				)
			)
		)
		(pad "2" smd custom
			(at 0 0.4445)
			(size 0.1397 0.1397)
			(layers "B.Cu" "B.Mask" "B.Paste")
			(net "I2C_DEBUG_SCL")
			(options
				(clearance outline)
				(anchor circle)
			)
			(primitives
				(gr_poly
					(pts
						(arc
							(start -0.1778 0.2794)
							(mid -0.249642 0.249642)
							(end -0.2794 0.1778)
						)
						(arc
							(start -0.2794 -0.1778)
							(mid -0.249642 -0.249642)
							(end -0.1778 -0.2794)
						)
						(arc
							(start 0.1778 -0.2794)
							(mid 0.249642 -0.249642)
							(end 0.2794 -0.1778)
						)
						(arc
							(start 0.2794 0.1778)
							(mid 0.249642 0.249642)
							(end 0.1778 0.2794)
						)
					)
					(width 0)
					(fill yes)
				)
			)
		)
	)
	(footprint ""
		(layer "B.Cu")
		(at 37.400738 -127.885698)
		(property "Reference" "R734"
			(at 0 0 0)
			(layer "B.SilkS")
			(hide yes)
			(effects
				(font
					(size 1.27 1.27)
				)
				(justify mirror)
			)
		)
		(property "Value" "0R2J-2-GP"
			(at -0.064008 -3.993896 0)
			(unlocked yes)
			(layer "B.Fab")
			(hide yes)
			(effects
				(font
					(size 1.016 1.016)
					(thickness 0.1524)
				)
				(justify mirror)
			)
		)
		(property "Device Type" "R402H16"
			(at -0.064008 -5.517896 0)
			(unlocked yes)
			(layer "B.Fab")
			(hide yes)
			(effects
				(font
					(size 1.016 1.016)
					(thickness 0.1524)
				)
				(justify mirror)
			)
		)
		(duplicate_pad_numbers_are_jumpers no)
		(fp_line
			(start -0.508 -0.9398)
			(end 0.508 -0.9398)
			(stroke
				(width 0.1524)
				(type default)
			)
			(layer "B.SilkS")
		)
		(fp_line
			(start 0.508 -0.9398)
			(end 0.508 0.9398)
			(stroke
				(width 0.1524)
				(type default)
			)
			(layer "B.SilkS")
		)
		(fp_rect
			(start 0.508 0.9398)
			(end -0.508 -0.9398)
			(stroke
				(width 0)
				(type default)
			)
			(fill no)
			(layer "B.CrtYd")
		)
		(fp_rect
			(start 0.508 0.9398)
			(end -0.508 -0.9398)
			(stroke
				(width 0)
				(type default)
			)
			(fill no)
			(layer "B.Fab")
		)
		(pad "1" smd custom
			(at 0 -0.4445 180)
			(size 0.1397 0.1397)
			(layers "B.Cu" "B.Mask" "B.Paste")
			(net "U104_EN")
			(options
				(clearance outline)
				(anchor circle)
			)
			(primitives
				(gr_poly
					(pts
						(arc
							(start -0.1778 0.2794)
							(mid -0.249642 0.249642)
							(end -0.2794 0.1778)
						)
						(arc
							(start -0.2794 -0.1778)
							(mid -0.249642 -0.249642)
							(end -0.1778 -0.2794)
						)
						(arc
							(start 0.1778 -0.2794)
							(mid 0.249642 -0.249642)
							(end 0.2794 -0.1778)
						)
						(arc
							(start 0.2794 0.1778)
							(mid 0.249642 0.249642)
							(end 0.1778 0.2794)
						)
					)
					(width 0)
					(fill yes)
				)
			)
		)
		(pad "2" smd custom
			(at 0 0.4445 180)
			(size 0.1397 0.1397)
			(layers "B.Cu" "B.Mask" "B.Paste")
			(net "SYS_RST_EN")
			(options
				(clearance outline)
				(anchor circle)
			)
			(primitives
				(gr_poly
					(pts
						(arc
							(start -0.1778 0.2794)
							(mid -0.249642 0.249642)
							(end -0.2794 0.1778)
						)
						(arc
							(start -0.2794 -0.1778)
							(mid -0.249642 -0.249642)
							(end -0.1778 -0.2794)
						)
						(arc
							(start 0.1778 -0.2794)
							(mid 0.249642 -0.249642)
							(end 0.2794 -0.1778)
						)
						(arc
							(start 0.2794 0.1778)
							(mid 0.249642 0.249642)
							(end 0.1778 0.2794)
						)
					)
					(width 0)
					(fill yes)
				)
			)
		)
	)
	(footprint ""
		(layer "B.Cu")
		(at 79.9592 -172.6438)
		(property "Reference" "R327"
			(at 0 0 0)
			(layer "B.SilkS")
			(hide yes)
			(effects
				(font
					(size 1.27 1.27)
				)
				(justify mirror)
			)
		)
		(property "Value" "4K7R2F-GP"
			(at -0.064008 -3.993896 0)
			(unlocked yes)
			(layer "B.Fab")
			(hide yes)
			(effects
				(font
					(size 1.016 1.016)
					(thickness 0.1524)
				)
				(justify mirror)
			)
		)
		(property "Device Type" "R402H16"
			(at -0.064008 -5.517896 0)
			(unlocked yes)
			(layer "B.Fab")
			(hide yes)
			(effects
				(font
					(size 1.016 1.016)
					(thickness 0.1524)
				)
				(justify mirror)
			)
		)
		(duplicate_pad_numbers_are_jumpers no)
		(fp_line
			(start -0.508 -0.9398)
			(end 0.508 -0.9398)
			(stroke
				(width 0.1524)
				(type default)
			)
			(layer "B.SilkS")
		)
		(fp_line
			(start 0.508 -0.9398)
			(end 0.508 0.9398)
			(stroke
				(width 0.1524)
				(type default)
			)
			(layer "B.SilkS")
		)
		(fp_rect
			(start 0.508 0.9398)
			(end -0.508 -0.9398)
			(stroke
				(width 0)
				(type default)
			)
			(fill no)
			(layer "B.CrtYd")
		)
		(fp_rect
			(start 0.508 0.9398)
			(end -0.508 -0.9398)
			(stroke
				(width 0)
				(type default)
			)
			(fill no)
			(layer "B.Fab")
		)
		(pad "1" smd custom
			(at 0 -0.4445 180)
			(size 0.1397 0.1397)
			(layers "B.Cu" "B.Mask" "B.Paste")
			(net "P3V3_STBY")
			(options
				(clearance outline)
				(anchor circle)
			)
			(primitives
				(gr_poly
					(pts
						(arc
							(start -0.1778 0.2794)
							(mid -0.249642 0.249642)
							(end -0.2794 0.1778)
						)
						(arc
							(start -0.2794 -0.1778)
							(mid -0.249642 -0.249642)
							(end -0.1778 -0.2794)
						)
						(arc
							(start 0.1778 -0.2794)
							(mid 0.249642 -0.249642)
							(end 0.2794 -0.1778)
						)
						(arc
							(start 0.2794 0.1778)
							(mid 0.249642 0.249642)
							(end 0.1778 0.2794)
						)
					)
					(width 0)
					(fill yes)
				)
			)
		)
		(pad "2" smd custom
			(at 0 0.4445 180)
			(size 0.1397 0.1397)
			(layers "B.Cu" "B.Mask" "B.Paste")
			(net "UART_EXP_BMC_RX")
			(options
				(clearance outline)
				(anchor circle)
			)
			(primitives
				(gr_poly
					(pts
						(arc
							(start -0.1778 0.2794)
							(mid -0.249642 0.249642)
							(end -0.2794 0.1778)
						)
						(arc
							(start -0.2794 -0.1778)
							(mid -0.249642 -0.249642)
							(end -0.1778 -0.2794)
						)
						(arc
							(start 0.1778 -0.2794)
							(mid 0.249642 -0.249642)
							(end 0.2794 -0.1778)
						)
						(arc
							(start 0.2794 0.1778)
							(mid 0.249642 0.249642)
							(end 0.1778 0.2794)
						)
					)
					(width 0)
					(fill yes)
				)
			)
		)
	)
	(footprint ""
		(layer "B.Cu")
		(at 192.11925 -133.831584 180)
		(property "Reference" "C613"
			(at 0 0 0)
			(layer "B.SilkS")
			(hide yes)
			(effects
				(font
					(size 1.27 1.27)
				)
				(justify mirror)
			)
		)
		(property "Value" "SCD1U16V2KX-3GP"
			(at -1.1811 -2.7051 180)
			(unlocked yes)
			(layer "B.Fab")
			(hide yes)
			(effects
				(font
					(size 1.016 1.016)
					(thickness 0.1524)
				)
				(justify mirror)
			)
		)
		(property "Device Type" "C402H22"
			(at -1.1811 -4.2291 180)
			(unlocked yes)
			(layer "B.Fab")
			(hide yes)
			(effects
				(font
					(size 1.016 1.016)
					(thickness 0.1524)
				)
				(justify mirror)
			)
		)
		(duplicate_pad_numbers_are_jumpers no)
		(fp_rect
			(start 0.4318 0.9525)
			(end -0.4318 -0.9525)
			(stroke
				(width 0)
				(type default)
			)
			(fill no)
			(layer "B.CrtYd")
		)
		(fp_rect
			(start 0.4318 0.9525)
			(end -0.4318 -0.9525)
			(stroke
				(width 0)
				(type default)
			)
			(fill no)
			(layer "B.Fab")
		)
		(pad "1" smd custom
			(at 0 -0.4445)
			(size 0.1524 0.1524)
			(layers "B.Cu" "B.Mask" "B.Paste")
			(net "P3V3_M2")
			(options
				(clearance outline)
				(anchor circle)
			)
			(primitives
				(gr_poly
					(pts
						(arc
							(start 0.3048 0.2032)
							(mid 0.275042 0.275042)
							(end 0.2032 0.3048)
						)
						(arc
							(start -0.2032 0.3048)
							(mid -0.275042 0.275042)
							(end -0.3048 0.2032)
						)
						(arc
							(start -0.3048 -0.2032)
							(mid -0.275042 -0.275042)
							(end -0.2032 -0.3048)
						)
						(arc
							(start 0.2032 -0.3048)
							(mid 0.275042 -0.275042)
							(end 0.3048 -0.2032)
						)
					)
					(width 0)
					(fill yes)
				)
			)
		)
		(pad "2" smd custom
			(at 0 0.4445)
			(size 0.1524 0.1524)
			(layers "B.Cu" "B.Mask" "B.Paste")
			(net "GND")
			(options
				(clearance outline)
				(anchor circle)
			)
			(primitives
				(gr_poly
					(pts
						(arc
							(start 0.3048 0.2032)
							(mid 0.275042 0.275042)
							(end 0.2032 0.3048)
						)
						(arc
							(start -0.2032 0.3048)
							(mid -0.275042 0.275042)
							(end -0.3048 0.2032)
						)
						(arc
							(start -0.3048 -0.2032)
							(mid -0.275042 -0.275042)
							(end -0.2032 -0.3048)
						)
						(arc
							(start 0.2032 -0.3048)
							(mid 0.275042 -0.275042)
							(end 0.3048 -0.2032)
						)
					)
					(width 0)
					(fill yes)
				)
			)
		)
	)
	(footprint ""
		(layer "B.Cu")
		(at 56.847232 -162.025076 90)
		(property "Reference" "R415"
			(at 0 0 90)
			(layer "B.SilkS")
			(hide yes)
			(effects
				(font
					(size 1.27 1.27)
				)
				(justify mirror)
			)
		)
		(property "Value" "1KR2F-3-GP"
			(at -0.064008 -3.993896 90)
			(unlocked yes)
			(layer "B.Fab")
			(hide yes)
			(effects
				(font
					(size 1.016 1.016)
					(thickness 0.1524)
				)
				(justify mirror)
			)
		)
		(property "Device Type" "R402H16"
			(at -0.064008 -5.517896 90)
			(unlocked yes)
			(layer "B.Fab")
			(hide yes)
			(effects
				(font
					(size 1.016 1.016)
					(thickness 0.1524)
				)
				(justify mirror)
			)
		)
		(duplicate_pad_numbers_are_jumpers no)
		(fp_line
			(start 0.508 -0.9398)
			(end 0.508 0.9398)
			(stroke
				(width 0.1524)
				(type default)
			)
			(layer "B.SilkS")
		)
		(fp_line
			(start -0.508 -0.9398)
			(end 0.508 -0.9398)
			(stroke
				(width 0.1524)
				(type default)
			)
			(layer "B.SilkS")
		)
		(fp_rect
			(start 0.508 0.9398)
			(end -0.508 -0.9398)
			(stroke
				(width 0)
				(type default)
			)
			(fill no)
			(layer "B.CrtYd")
		)
		(fp_rect
			(start 0.508 0.9398)
			(end -0.508 -0.9398)
			(stroke
				(width 0)
				(type default)
			)
			(fill no)
			(layer "B.Fab")
		)
		(pad "1" smd custom
			(at 0 -0.4445 270)
			(size 0.1397 0.1397)
			(layers "B.Cu" "B.Mask" "B.Paste")
			(net "ADC_P5V_STBY")
			(options
				(clearance outline)
				(anchor circle)
			)
			(primitives
				(gr_poly
					(pts
						(arc
							(start -0.1778 0.2794)
							(mid -0.249642 0.249642)
							(end -0.2794 0.1778)
						)
						(arc
							(start -0.2794 -0.1778)
							(mid -0.249642 -0.249642)
							(end -0.1778 -0.2794)
						)
						(arc
							(start 0.1778 -0.2794)
							(mid 0.249642 -0.249642)
							(end 0.2794 -0.1778)
						)
						(arc
							(start 0.2794 0.1778)
							(mid 0.249642 0.249642)
							(end 0.1778 0.2794)
						)
					)
					(width 0)
					(fill yes)
				)
			)
		)
		(pad "2" smd custom
			(at 0 0.4445 270)
			(size 0.1397 0.1397)
			(layers "B.Cu" "B.Mask" "B.Paste")
			(net "GND")
			(options
				(clearance outline)
				(anchor circle)
			)
			(primitives
				(gr_poly
					(pts
						(arc
							(start -0.1778 0.2794)
							(mid -0.249642 0.249642)
							(end -0.2794 0.1778)
						)
						(arc
							(start -0.2794 -0.1778)
							(mid -0.249642 -0.249642)
							(end -0.1778 -0.2794)
						)
						(arc
							(start 0.1778 -0.2794)
							(mid 0.249642 -0.249642)
							(end 0.2794 -0.1778)
						)
						(arc
							(start 0.2794 0.1778)
							(mid 0.249642 0.249642)
							(end 0.1778 0.2794)
						)
					)
					(width 0)
					(fill yes)
				)
			)
		)
	)
)
